(kicad_pcb
	(version 20260206)
	(generator "pcbnew")
	(generator_version "10.0")
	(general
		(thickness 1.6)
		(legacy_teardrops no)
	)
	(paper "A4")
	(title_block
		(title "9052_F0T_PDB_Converter_Brick_F_V03_1208_1600_OCP.brd")
		(comment 1 "Grand Teton / footprints 41-41 of 578")
	)
	(layers
		(0 "F.Cu" signal "TOP")
		(4 "In1.Cu" signal "GND")
		(6 "In2.Cu" signal "IN1")
		(8 "In3.Cu" signal "GND1")
		(10 "In4.Cu" signal "VCC")
		(12 "In5.Cu" signal "VCC1")
		(14 "In6.Cu" signal "GND2")
		(16 "In7.Cu" signal "IN2")
		(18 "In8.Cu" signal "GND3")
		(2 "B.Cu" signal "BOTTOM")
		(9 "F.Adhes" user "F.Adhesive")
		(11 "B.Adhes" user "B.Adhesive")
		(13 "F.Paste" user "Package Geometry/Pastemask Top")
		(15 "B.Paste" user "Package Geometry/Pastemask Bottom")
		(5 "F.SilkS" user "Ref Des/Silkscreen Top")
		(7 "B.SilkS" user "Ref Des/Silkscreen Bottom")
		(1 "F.Mask" user "Board Geometry/Soldermask Top")
		(3 "B.Mask" user "Board Geometry/Soldermask Bottom")
		(17 "Dwgs.User" user "User.Drawings")
		(19 "Cmts.User" user "User.Comments")
		(21 "Eco1.User" user "User.Eco1")
		(23 "Eco2.User" user "User.Eco2")
		(25 "Edge.Cuts" user "Board Geometry/Outline")
		(27 "Margin" user)
		(31 "F.CrtYd" user "Package Geometry/Place Bound Top")
		(29 "B.CrtYd" user "Package Geometry/Place Bound Bottom")
		(35 "F.Fab" user "Ref Des/Assembly Top")
		(33 "B.Fab" user "Ref Des/Assembly Bottom")
	)
	(footprint ""
		(layer "F.Cu")
		(at 263.792716 -41.342818)
		(property "Reference" "PU1"
			(at -5.347716 -4.223512 0)
			(unlocked yes)
			(layer "F.SilkS")
			(effects
				(font
					(size 0.7874 0.5842)
					(thickness 0.1524)
				)
				(justify left)
			)
		)
		(property "Value" ""
			(at 0 0 0)
			(layer "F.Fab")
			(effects
				(font
					(size 1.27 1.27)
				)
			)
		)
		(duplicate_pad_numbers_are_jumpers no)
		(fp_line
			(start -3.549904 -3.549904)
			(end -3.0226 -3.549904)
			(stroke
				(width 0.1524)
				(type default)
			)
			(layer "F.SilkS")
		)
		(fp_line
			(start -3.549904 -3.0226)
			(end -3.549904 -3.549904)
			(stroke
				(width 0.1524)
				(type default)
			)
			(layer "F.SilkS")
		)
		(fp_line
			(start -3.549904 -0.0254)
			(end -3.549904 -1.4732)
			(stroke
				(width 0.1524)
				(type default)
			)
			(layer "F.SilkS")
		)
		(fp_line
			(start -3.549904 3.549904)
			(end -3.549904 3.0226)
			(stroke
				(width 0.1524)
				(type default)
			)
			(layer "F.SilkS")
		)
		(fp_line
			(start -3.0226 3.549904)
			(end -3.549904 3.549904)
			(stroke
				(width 0.1524)
				(type default)
			)
			(layer "F.SilkS")
		)
		(fp_line
			(start -2.4638 -3.549904)
			(end -1.03124 -3.549904)
			(stroke
				(width 0.1524)
				(type default)
			)
			(layer "F.SilkS")
		)
		(fp_line
			(start -1.03124 3.549904)
			(end -2.4638 3.549904)
			(stroke
				(width 0.1524)
				(type default)
			)
			(layer "F.SilkS")
		)
		(fp_line
			(start 3.0226 -3.549904)
			(end 3.549904 -3.549904)
			(stroke
				(width 0.1524)
				(type default)
			)
			(layer "F.SilkS")
		)
		(fp_line
			(start 3.549904 -3.549904)
			(end 3.549904 -3.0226)
			(stroke
				(width 0.1524)
				(type default)
			)
			(layer "F.SilkS")
		)
		(fp_line
			(start 3.549904 3.0226)
			(end 3.549904 3.549904)
			(stroke
				(width 0.1524)
				(type default)
			)
			(layer "F.SilkS")
		)
		(fp_line
			(start 3.549904 3.549904)
			(end 3.0226 3.549904)
			(stroke
				(width 0.1524)
				(type default)
			)
			(layer "F.SilkS")
		)
		(fp_poly
			(pts
				(xy -4.134104 -3.041904) (xy -3.549904 -3.041904) (xy -3.549904 -3.626104) (xy -4.134104 -3.626104)
			)
			(stroke
				(width 0)
				(type default)
			)
			(fill yes)
			(layer "F.SilkS")
		)
		(fp_line
			(start -3.549904 -3.549904)
			(end 3.549904 -3.549904)
			(stroke
				(width 0.1)
				(type default)
			)
			(layer "F.Fab")
		)
		(fp_line
			(start -3.549904 3.549904)
			(end -3.549904 -3.549904)
			(stroke
				(width 0.1)
				(type default)
			)
			(layer "F.Fab")
		)
		(fp_line
			(start 3.549904 -3.549904)
			(end 3.549904 3.549904)
			(stroke
				(width 0.1)
				(type default)
			)
			(layer "F.Fab")
		)
		(fp_line
			(start 3.549904 3.549904)
			(end -3.549904 3.549904)
			(stroke
				(width 0.1)
				(type default)
			)
			(layer "F.Fab")
		)
		(fp_poly
			(pts
				(xy -4.134104 -3.041904) (xy -3.549904 -3.041904) (xy -3.549904 -3.626104) (xy -4.134104 -3.626104)
			)
			(stroke
				(width 0)
				(type default)
			)
			(fill yes)
			(layer "F.Fab")
		)
		(pad "1" smd rect
			(at -3.425444 -2.750058 270)
			(size 0.2794 0.7112)
			(layers "F.Cu" "F.Mask" "F.Paste")
			(net "P52V_HS")
		)
		(pad "2" smd rect
			(at -3.400044 -2.249932 270)
			(size 0.2794 0.762)
			(layers "F.Cu" "F.Mask" "F.Paste")
			(net "P52V_HS1_4287_GATE2_R")
		)
		(pad "3" smd rect
			(at -3.400044 -1.75006 270)
			(size 0.2794 0.762)
			(layers "F.Cu" "F.Mask" "F.Paste")
			(net "P52V_HS1_4287_GATE_R")
		)
		(pad "4" smd rect
			(at -3.400044 0.249936 270)
			(size 0.2794 0.762)
			(layers "F.Cu" "F.Mask" "F.Paste")
			(net "P52V_HS_4287_ADC_N")
		)
		(pad "5" smd rect
			(at -3.400044 0.750062 270)
			(size 0.2794 0.762)
			(layers "F.Cu" "F.Mask" "F.Paste")
			(net "P52V_HS_4287_S1N")
		)
		(pad "6" smd rect
			(at -3.400044 1.249934 270)
			(size 0.2794 0.762)
			(layers "F.Cu" "F.Mask" "F.Paste")
			(net "P52V_HS_4287_S1P")
		)
		(pad "7" smd rect
			(at -3.400044 1.75006 270)
			(size 0.2794 0.762)
			(layers "F.Cu" "F.Mask" "F.Paste")
			(net "P52V_HS_4287_ADC_P")
		)
		(pad "8" smd rect
			(at -3.400044 2.249932 270)
			(size 0.2794 0.762)
			(layers "F.Cu" "F.Mask" "F.Paste")
			(net "P52V_HS_4287_S2N")
		)
		(pad "9" smd rect
			(at -3.425444 2.750058 270)
			(size 0.2794 0.7112)
			(layers "F.Cu" "F.Mask" "F.Paste")
			(net "P52V_HS_4287_S2P")
		)
		(pad "10" smd rect
			(at -2.750058 3.425444)
			(size 0.2794 0.7112)
			(layers "F.Cu" "F.Mask" "F.Paste")
			(net "P52V_1_R")
		)
		(pad "11" smd rect
			(at -0.750062 3.400044)
			(size 0.2794 0.762)
			(layers "F.Cu" "F.Mask" "F.Paste")
			(net "P52V_HS1_UVLO_EN")
		)
		(pad "12" smd rect
			(at -0.249936 3.400044)
			(size 0.2794 0.762)
			(layers "F.Cu" "F.Mask" "F.Paste")
			(net "P52V_HS1_OV")
		)
		(pad "13" smd rect
			(at 0.249936 3.400044)
			(size 0.2794 0.762)
			(layers "F.Cu" "F.Mask" "F.Paste")
			(net "P52V_HS1_INTVCC")
		)
		(pad "14" smd rect
			(at 0.750062 3.400044)
			(size 0.2794 0.762)
			(layers "F.Cu" "F.Mask" "F.Paste")
			(net "GND_FIELD_SIGNAL")
		)
		(pad "15" smd rect
			(at 1.249934 3.400044)
			(size 0.2794 0.762)
			(layers "F.Cu" "F.Mask" "F.Paste")
			(net "P52V_HS1_DVCC")
		)
		(pad "16" smd rect
			(at 1.75006 3.400044)
			(size 0.2794 0.762)
			(layers "F.Cu" "F.Mask" "F.Paste")
			(net "P52V_HS1_ADR0")
		)
		(pad "17" smd rect
			(at 2.249932 3.400044)
			(size 0.2794 0.762)
			(layers "F.Cu" "F.Mask" "F.Paste")
			(net "P52V_HS1_ADR1")
		)
		(pad "18" smd rect
			(at 2.750058 3.425444)
			(size 0.2794 0.7112)
			(layers "F.Cu" "F.Mask" "F.Paste")
			(net "Net_299")
		)
		(pad "19" smd rect
			(at 3.425444 2.750058 270)
			(size 0.2794 0.7112)
			(layers "F.Cu" "F.Mask" "F.Paste")
			(net "P52V_HS1_MODE")
		)
		(pad "20" smd rect
			(at 3.400044 2.249932 270)
			(size 0.2794 0.762)
			(layers "F.Cu" "F.Mask" "F.Paste")
			(net "P52V_HS1_TMR")
		)
		(pad "21" smd rect
			(at 3.400044 1.75006 270)
			(size 0.2794 0.762)
			(layers "F.Cu" "F.Mask" "F.Paste")
			(net "P52V_HS1_CLKIN")
		)
		(pad "22" smd rect
			(at 3.400044 1.249934 270)
			(size 0.2794 0.762)
			(layers "F.Cu" "F.Mask" "F.Paste")
			(net "Net_303")
		)
		(pad "23" smd rect
			(at 3.400044 0.750062 270)
			(size 0.2794 0.762)
			(layers "F.Cu" "F.Mask" "F.Paste")
			(net "P52V_HS1_EN_BUF_DELAY")
		)
		(pad "24" smd rect
			(at 3.400044 0.249936 270)
			(size 0.2794 0.762)
			(layers "F.Cu" "F.Mask" "F.Paste")
			(net "P52V_HS1_SIO")
		)
		(pad "25" smd rect
			(at 3.400044 -0.249936 270)
			(size 0.2794 0.762)
			(layers "F.Cu" "F.Mask" "F.Paste")
			(net "P52V_HS1_SCK")
		)
		(pad "26" smd rect
			(at 3.400044 -0.750062 270)
			(size 0.2794 0.762)
			(layers "F.Cu" "F.Mask" "F.Paste")
			(net "P52V_HS1_CS")
		)
		(pad "27" smd rect
			(at 3.400044 -1.249934 270)
			(size 0.2794 0.762)
			(layers "F.Cu" "F.Mask" "F.Paste")
			(net "SMB_P52V_VPDB_SCL_R3")
		)
		(pad "28" smd rect
			(at 3.400044 -1.75006 270)
			(size 0.2794 0.762)
			(layers "F.Cu" "F.Mask" "F.Paste")
			(net "SMB_P52V_HS1_SDAI")
		)
		(pad "29" smd rect
			(at 3.400044 -2.249932 270)
			(size 0.2794 0.762)
			(layers "F.Cu" "F.Mask" "F.Paste")
			(net "SMB_P52V_HS1_SDAO")
		)
		(pad "30" smd rect
			(at 3.425444 -2.750058 270)
			(size 0.2794 0.7112)
			(layers "F.Cu" "F.Mask" "F.Paste")
			(net "Net_300")
		)
		(pad "31" smd rect
			(at 2.750058 -3.425444)
			(size 0.2794 0.7112)
			(layers "F.Cu" "F.Mask" "F.Paste")
			(net "Net_301")
		)
		(pad "32" smd rect
			(at 2.249932 -3.400044)
			(size 0.2794 0.762)
			(layers "F.Cu" "F.Mask" "F.Paste")
			(net "Net_302")
		)
		(pad "33" smd rect
			(at 1.75006 -3.400044)
			(size 0.2794 0.762)
			(layers "F.Cu" "F.Mask" "F.Paste")
			(net "GND_FIELD_SIGNAL")
		)
		(pad "34" smd rect
			(at 1.249934 -3.400044)
			(size 0.2794 0.762)
			(layers "F.Cu" "F.Mask" "F.Paste")
			(net "GND_FIELD_SIGNAL")
		)
		(pad "35" smd rect
			(at 0.750062 -3.400044)
			(size 0.2794 0.762)
			(layers "F.Cu" "F.Mask" "F.Paste")
			(net "P52V_HS1_TEMP")
		)
		(pad "36" smd rect
			(at 0.249936 -3.400044)
			(size 0.2794 0.762)
			(layers "F.Cu" "F.Mask" "F.Paste")
			(net "P52V_HS1_FLT")
		)
		(pad "37" smd rect
			(at -0.249936 -3.400044)
			(size 0.2794 0.762)
			(layers "F.Cu" "F.Mask" "F.Paste")
			(net "PWRGD_P52V_HS1_PG_N")
		)
		(pad "38" smd rect
			(at -0.750062 -3.400044)
			(size 0.2794 0.762)
			(layers "F.Cu" "F.Mask" "F.Paste")
			(net "P52V_HS1_FB")
		)
		(pad "39" smd rect
			(at -2.750058 -3.425444)
			(size 0.2794 0.7112)
			(layers "F.Cu" "F.Mask" "F.Paste")
			(net "P52V_HS1_VDSFB")
		)
		(pad "40" smd circle
			(at 0.87503 0)
			(size 0 0)
			(layers "F.Cu" "F.Mask" "F.Paste")
			(net "GND_FIELD_SIGNAL")
		)
		(zone
			(layer "F.Cu")
			(hatch none 0.5)
			(connect_pads
				(clearance 0)
			)
			(min_thickness 0.25)
			(keepout
				(tracks not_allowed)
				(vias allowed)
				(pads allowed)
				(copperpour not_allowed)
				(footprints allowed)
			)
			(placement
				(enabled no)
				(sheetname "")
			)
			(fill
				(thermal_gap 0.5)
				(thermal_bridge_width 0.5)
				(island_removal_mode 0)
			)
			(polygon
				(pts
					(xy 260.824472 -43.786298) (xy 260.824472 -42.003218) (xy 262.776716 -42.003218) (xy 262.776716 -43.730418)
					(xy 263.157716 -44.111418) (xy 266.561316 -44.111418) (xy 266.561316 -38.574218) (xy 262.776716 -38.574218)
					(xy 262.776716 -41.977818) (xy 260.824472 -41.977818) (xy 260.824472 -38.896798) (xy 260.773672 -38.896798)
					(xy 260.773672 -38.323774) (xy 262.845296 -38.323774) (xy 262.845296 -38.374574) (xy 266.238736 -38.374574)
					(xy 266.238736 -38.323774) (xy 266.81176 -38.323774) (xy 266.81176 -38.896798) (xy 266.76096 -38.896798)
					(xy 266.76096 -43.788838) (xy 266.81176 -43.788838) (xy 266.81176 -44.361862) (xy 266.238736 -44.361862)
					(xy 266.238736 -44.311062) (xy 262.845296 -44.311062) (xy 262.845296 -44.361862) (xy 260.773672 -44.361862)
					(xy 260.773672 -43.786298)
				)
			)
		)
	)
)
